G04 ================== begin FILE IDENTIFICATION RECORD ==================*
G04 Layout Name:  12433-1M.brd*
G04 Film Name:    BMASK*
G04 File Format:  Gerber RS274X*
G04 File Origin:  Cadence Allegro 16.2-S037*
G04 Origin Date:  Fri Dec 07 18:55:03 2012*
G04 *
G04 Layer:  VIA CLASS/SOLDERMASK_BOTTOM*
G04 Layer:  PIN/SOLDERMASK_BOTTOM*
G04 Layer:  PACKAGE GEOMETRY/SOLDERMASK_BOTTOM*
G04 Layer:  DRAWING FORMAT/LAYER_PCB_STORY*
G04 Layer:  DRAWING FORMAT/LAYER_SOLDER_B*
G04 Layer:  BOARD GEOMETRY/SOLDERMASK_BOTTOM*
G04 *
G04 Offset:    (0.00 0.00)*
G04 Mirror:    No*
G04 Mode:      Positive*
G04 Rotation:  0*
G04 FullContactRelief:  No*
G04 UndefLineWidth:     6.00*
G04 ================== end FILE IDENTIFICATION RECORD ====================*
%FSLAX35Y35*MOIN*%
%IR0*IPPOS*OFA0.00000B0.00000*MIA0B0*SFA1.00000B1.00000*%
%ADD15C,.05*%
%ADD16C,.028*%
%ADD13C,.056*%
%ADD20C,.057*%
%ADD19C,.099*%
%ADD10C,.14*%
%ADD17C,.115*%
%ADD12C,.142*%
%ADD18C,.126*%
%ADD14C,.315*%
%ADD22R,.12X.12*%
%ADD11R,.16X.16*%
%ADD21C,.375*%
%ADD23C,.02*%
%ADD24C,.006*%
G75*
%LPD*%
G75*
G54D10*
X-222440Y19685D03*
Y1948818D03*
X643700Y19685D03*
Y1948818D03*
G54D11*
X-181139Y20007D03*
X-180444Y1947256D03*
X601704Y21248D03*
X602399Y1948497D03*
G54D20*
X80709Y161889D03*
Y171889D03*
Y181889D03*
Y191889D03*
Y204409D03*
Y214409D03*
Y224409D03*
Y234409D03*
Y244409D03*
Y256929D03*
Y266929D03*
Y276929D03*
Y286929D03*
X110709Y161889D03*
Y171889D03*
X100709Y161889D03*
Y171889D03*
X90709Y161889D03*
Y171889D03*
X110709Y181889D03*
Y191889D03*
X100709Y181889D03*
Y191889D03*
X90709Y181889D03*
Y191889D03*
X110709Y204409D03*
Y214409D03*
Y224409D03*
Y234409D03*
Y244409D03*
X100709Y204409D03*
Y214409D03*
Y224409D03*
Y234409D03*
Y244409D03*
X90709Y204409D03*
Y214409D03*
Y224409D03*
Y234409D03*
Y244409D03*
X110709Y256929D03*
Y266929D03*
X100709Y256929D03*
Y266929D03*
X90709Y256929D03*
Y266929D03*
X110709Y276929D03*
Y286929D03*
X100709Y276929D03*
Y286929D03*
X90709Y276929D03*
Y286929D03*
X179606Y161889D03*
Y171889D03*
X169606Y161889D03*
Y171889D03*
X159606Y161889D03*
Y171889D03*
X149606Y161889D03*
Y171889D03*
X179606Y181889D03*
Y191889D03*
X169606Y181889D03*
Y191889D03*
X159606Y181889D03*
Y191889D03*
X149606Y181889D03*
Y191889D03*
X179606Y204409D03*
Y214409D03*
Y224409D03*
Y234409D03*
Y244409D03*
X169606Y204409D03*
Y214409D03*
Y224409D03*
Y234409D03*
Y244409D03*
X159606Y204409D03*
Y214409D03*
Y224409D03*
Y234409D03*
Y244409D03*
X149606Y204409D03*
Y214409D03*
Y224409D03*
Y234409D03*
Y244409D03*
X179606Y256929D03*
Y266929D03*
X169606Y256929D03*
Y266929D03*
X159606Y256929D03*
Y266929D03*
X149606Y256929D03*
Y266929D03*
X179606Y276929D03*
Y286929D03*
X169606Y276929D03*
Y286929D03*
X159606Y276929D03*
Y286929D03*
X149606Y276929D03*
Y286929D03*
G54D21*
X96457Y1747835D03*
Y1823031D03*
X178937Y1328740D03*
X161417Y1747835D03*
Y1823031D03*
G54D12*
X29921Y24803D03*
Y111417D03*
Y458031D03*
Y544646D03*
Y717874D03*
Y804488D03*
X30000Y1164000D03*
X29921Y1250630D03*
Y1423858D03*
Y1510472D03*
Y1857086D03*
Y1943701D03*
G54D22*
X150000Y64500D03*
X152500Y1906000D03*
G54D13*
X15906Y48110D03*
Y58110D03*
Y68110D03*
Y78110D03*
Y88110D03*
Y481339D03*
Y491339D03*
Y501339D03*
Y511339D03*
Y521339D03*
Y741181D03*
Y751181D03*
Y761181D03*
Y771181D03*
Y781181D03*
Y1187323D03*
Y1197323D03*
Y1207323D03*
Y1217323D03*
Y1227323D03*
Y1447165D03*
Y1457165D03*
Y1467165D03*
Y1477165D03*
Y1487165D03*
Y1880394D03*
Y1890394D03*
Y1900394D03*
Y1910394D03*
Y1920394D03*
X128937Y1778819D03*
X118937D03*
X165000Y1390500D03*
Y1380500D03*
Y1370500D03*
X138937Y1778819D03*
G54D23*
G01X-448201Y-82763D02*
Y-162763D01*
G01Y-118263D02*
X752899D01*
G01X-448201Y-162763D02*
X752899D01*
G01X-452201Y-66763D02*
G02I-12000J0D01*
G01X-457351D02*
G02I-6850J0D01*
G01X-464201Y-82763D02*
Y-50763D01*
G01X-448201Y-66763D02*
X-480201D01*
G01X-448201Y-82763D02*
X752899D01*
G01X-34601D02*
Y-162763D01*
G01X102899Y-82763D02*
Y-162763D01*
G01X217899Y-82763D02*
Y-162763D01*
G01X385399Y-82763D02*
Y-162763D01*
G01X555399Y-82763D02*
Y-162763D01*
G01X752899Y-82763D02*
Y-162763D01*
G01X780899Y-66763D02*
G02I-12000J0D01*
G01X775749D02*
G02I-6850J0D01*
G01X768899Y-82763D02*
Y-50763D01*
G01X784899Y-66763D02*
X752899D01*
G54D14*
X27559Y157480D03*
Y629921D03*
X17716Y1338583D03*
X27559Y1811023D03*
X179134Y78740D03*
X179133Y570866D03*
X179134Y1161417D03*
Y1889764D03*
G54D24*
G01X-430254Y-152763D02*
Y-135263D01*
G01X-421958D02*
X-430254Y-146055D01*
G01X-420648Y-152763D02*
X-426543Y-141097D01*
G01X-412973Y-152763D02*
Y-135263D01*
X-402929Y-152763D01*
Y-135263D01*
G01X-390451Y-152763D02*
X-392198Y-152471D01*
X-393726Y-151305D01*
X-395036Y-149555D01*
X-395910Y-147513D01*
X-396346Y-145180D01*
Y-142846D01*
X-395910Y-140513D01*
X-395036Y-138471D01*
X-393726Y-136722D01*
X-392198Y-135555D01*
X-390451Y-135263D01*
X-388705Y-135555D01*
X-387176Y-136722D01*
X-385866Y-138471D01*
X-384992Y-140513D01*
X-384556Y-142846D01*
Y-145180D01*
X-384992Y-147513D01*
X-385866Y-149555D01*
X-387176Y-151305D01*
X-388705Y-152471D01*
X-390451Y-152763D01*
G01X-377536D02*
X-368366Y-135263D01*
G01X-377536D02*
X-368366Y-152763D01*
G01X-362001Y-158596D02*
X-348901D01*
G01X-342099Y-152763D02*
Y-135263D01*
X-333803D01*
G01X-336859Y-143721D02*
X-342099D01*
G01X-325910Y-152763D02*
X-320451Y-135263D01*
X-314992Y-152763D01*
G01X-316958Y-146638D02*
X-323945D01*
G01X-307973Y-152763D02*
Y-135263D01*
X-297929Y-152763D01*
Y-135263D01*
G01X-263148Y-136722D02*
X-264458Y-135846D01*
X-265986Y-135263D01*
X-267733D01*
X-269698Y-136138D01*
X-271226Y-137596D01*
X-272318Y-139347D01*
X-273191Y-142263D01*
X-273410Y-144888D01*
X-272973Y-147513D01*
X-272318Y-149263D01*
X-271008Y-151013D01*
X-269479Y-152180D01*
X-267951Y-152763D01*
X-266423D01*
X-264894Y-152180D01*
X-263584Y-151305D01*
X-262492Y-150139D01*
G01X-250451Y-152763D02*
X-252198Y-152471D01*
X-253726Y-151305D01*
X-255036Y-149555D01*
X-255910Y-147513D01*
X-256346Y-145180D01*
Y-142846D01*
X-255910Y-140513D01*
X-255036Y-138471D01*
X-253726Y-136722D01*
X-252198Y-135555D01*
X-250451Y-135263D01*
X-248705Y-135555D01*
X-247176Y-136722D01*
X-245866Y-138471D01*
X-244992Y-140513D01*
X-244556Y-142846D01*
Y-145180D01*
X-244992Y-147513D01*
X-245866Y-149555D01*
X-247176Y-151305D01*
X-248705Y-152471D01*
X-250451Y-152763D01*
G01X-237973D02*
Y-135263D01*
X-227929Y-152763D01*
Y-135263D01*
G01X-215451D02*
Y-152763D01*
G01X-220473Y-135263D02*
X-210429D01*
G01X-202318Y-152763D02*
Y-135263D01*
X-196859D01*
X-195113Y-136138D01*
X-194021Y-137305D01*
X-193584Y-139638D01*
X-194021Y-141972D01*
X-195331Y-143430D01*
X-196859Y-144305D01*
X-202318D01*
G01X-196859D02*
X-193584Y-152763D01*
G01X-180451D02*
X-182198Y-152471D01*
X-183726Y-151305D01*
X-185036Y-149555D01*
X-185910Y-147513D01*
X-186346Y-145180D01*
Y-142846D01*
X-185910Y-140513D01*
X-185036Y-138471D01*
X-183726Y-136722D01*
X-182198Y-135555D01*
X-180451Y-135263D01*
X-178705Y-135555D01*
X-177176Y-136722D01*
X-175866Y-138471D01*
X-174992Y-140513D01*
X-174556Y-142846D01*
Y-145180D01*
X-174992Y-147513D01*
X-175866Y-149555D01*
X-177176Y-151305D01*
X-178705Y-152471D01*
X-180451Y-152763D01*
G01X-167318Y-135263D02*
Y-152763D01*
X-158584D01*
G01X-126205Y-143430D02*
X-125331Y-142555D01*
X-124676Y-141097D01*
X-124239Y-139054D01*
X-124676Y-137305D01*
X-125549Y-136138D01*
X-127078Y-135263D01*
X-132973D01*
Y-152763D01*
X-125768D01*
X-124239Y-151597D01*
X-123366Y-149846D01*
X-122929Y-147805D01*
X-123366Y-145763D01*
X-124676Y-144013D01*
X-126205Y-143430D01*
X-132973D01*
G01X-110451Y-152763D02*
X-112198Y-152471D01*
X-113726Y-151305D01*
X-115036Y-149555D01*
X-115910Y-147513D01*
X-116346Y-145180D01*
Y-142846D01*
X-115910Y-140513D01*
X-115036Y-138471D01*
X-113726Y-136722D01*
X-112198Y-135555D01*
X-110451Y-135263D01*
X-108705Y-135555D01*
X-107176Y-136722D01*
X-105866Y-138471D01*
X-104992Y-140513D01*
X-104556Y-142846D01*
Y-145180D01*
X-104992Y-147513D01*
X-105866Y-149555D01*
X-107176Y-151305D01*
X-108705Y-152471D01*
X-110451Y-152763D01*
G01X-98410D02*
X-92951Y-135263D01*
X-87492Y-152763D01*
G01X-89458Y-146638D02*
X-96445D01*
G01X-79818Y-152763D02*
Y-135263D01*
X-74359D01*
X-72613Y-136138D01*
X-71521Y-137305D01*
X-71084Y-139638D01*
X-71521Y-141972D01*
X-72831Y-143430D01*
X-74359Y-144305D01*
X-79818D01*
G01X-74359D02*
X-71084Y-152763D01*
G01X-62754D02*
Y-135263D01*
X-58388D01*
X-56641Y-136138D01*
X-55331Y-137305D01*
X-54239Y-139054D01*
X-53366Y-141097D01*
X-53148Y-144013D01*
X-53366Y-146930D01*
X-54239Y-148972D01*
X-55331Y-150722D01*
X-56641Y-151888D01*
X-58388Y-152763D01*
X-62754D01*
G01X-282378Y-107763D02*
Y-90263D01*
X-276701Y-104846D01*
X-271024Y-90263D01*
Y-107763D01*
G01X-259201D02*
X-260511Y-107471D01*
X-261821Y-106305D01*
X-262695Y-104263D01*
X-263131Y-101930D01*
X-262695Y-99596D01*
X-261821Y-97555D01*
X-260511Y-96388D01*
X-259201Y-96097D01*
X-257891Y-96388D01*
X-256581Y-97555D01*
X-255708Y-99596D01*
X-255489Y-101930D01*
X-255708Y-104263D01*
X-256581Y-106305D01*
X-257891Y-107471D01*
X-259201Y-107763D01*
G01X-237771Y-90263D02*
Y-107763D01*
G01Y-105139D02*
X-238644Y-106597D01*
X-239955Y-107471D01*
X-241483Y-107763D01*
X-243229Y-107180D01*
X-244539Y-105722D01*
X-245413Y-103972D01*
X-245631Y-101930D01*
X-245413Y-99888D01*
X-244539Y-98138D01*
X-243229Y-96680D01*
X-241483Y-96097D01*
X-239955Y-96388D01*
X-238863Y-96972D01*
X-237771Y-98138D01*
G01X-227476Y-99888D02*
X-220489D01*
X-221144Y-97846D01*
X-222236Y-96680D01*
X-223764Y-96097D01*
X-225293Y-96388D01*
X-226603Y-97263D01*
X-227476Y-99305D01*
X-227913Y-101055D01*
Y-102805D01*
X-227476Y-104555D01*
X-226384Y-106305D01*
X-225074Y-107471D01*
X-223546Y-107763D01*
X-222018Y-107180D01*
X-220489Y-105430D01*
G01X-206701Y-107763D02*
Y-90263D01*
G01X-901Y-152763D02*
Y-135263D01*
X-3521Y-138763D01*
G01Y-152763D02*
X1719D01*
G01X12451Y-138180D02*
X13761Y-136430D01*
X15289Y-135555D01*
X17036Y-135263D01*
X19219Y-135846D01*
X20747Y-137305D01*
X21184Y-139054D01*
X20966Y-140805D01*
X20092Y-142263D01*
X15726Y-145180D01*
X13761Y-147221D01*
X12451Y-150139D01*
X12014Y-152763D01*
X21184D01*
G01X36719D02*
Y-135263D01*
X28640Y-147805D01*
X39558D01*
G01X46796Y-149263D02*
X48105Y-151305D01*
X49852Y-152471D01*
X51817Y-152763D01*
X53564Y-152471D01*
X55311Y-151013D01*
X56402Y-149263D01*
X56621Y-147513D01*
X56184Y-145472D01*
X54656Y-144013D01*
X53127Y-143430D01*
X51162D01*
G01X53127D02*
X54437Y-142555D01*
X55529Y-141097D01*
X55966Y-139347D01*
X55529Y-137596D01*
X54437Y-136138D01*
X52472Y-135263D01*
X50507Y-135555D01*
X48542Y-136722D01*
G01X64296Y-149263D02*
X65605Y-151305D01*
X67352Y-152471D01*
X69317Y-152763D01*
X71064Y-152471D01*
X72811Y-151013D01*
X73902Y-149263D01*
X74121Y-147513D01*
X73684Y-145472D01*
X72156Y-144013D01*
X70627Y-143430D01*
X68662D01*
G01X70627D02*
X71937Y-142555D01*
X73029Y-141097D01*
X73466Y-139347D01*
X73029Y-137596D01*
X71937Y-136138D01*
X69972Y-135263D01*
X68007Y-135555D01*
X66042Y-136722D01*
G01X-14018Y-107763D02*
Y-90263D01*
X-8778D01*
X-7031Y-91138D01*
X-5721Y-93180D01*
X-5284Y-95513D01*
X-5721Y-97846D01*
X-6813Y-99596D01*
X-8778Y-100472D01*
X-14018D01*
G01X12652Y-91722D02*
X11342Y-90846D01*
X9814Y-90263D01*
X8067D01*
X6102Y-91138D01*
X4574Y-92596D01*
X3482Y-94347D01*
X2609Y-97263D01*
X2390Y-99888D01*
X2827Y-102513D01*
X3482Y-104263D01*
X4792Y-106013D01*
X6321Y-107180D01*
X7849Y-107763D01*
X9377D01*
X10906Y-107180D01*
X12216Y-106305D01*
X13308Y-105139D01*
G01X27095Y-98430D02*
X27969Y-97555D01*
X28624Y-96097D01*
X29061Y-94054D01*
X28624Y-92305D01*
X27751Y-91138D01*
X26222Y-90263D01*
X20327D01*
Y-107763D01*
X27532D01*
X29061Y-106597D01*
X29934Y-104846D01*
X30371Y-102805D01*
X29934Y-100763D01*
X28624Y-99013D01*
X27095Y-98430D01*
X20327D01*
G01X36299Y-113596D02*
X49399D01*
G01X55327Y-107763D02*
Y-90263D01*
X65371Y-107763D01*
Y-90263D01*
G01X77849Y-107763D02*
X76102Y-107471D01*
X74574Y-106305D01*
X73264Y-104555D01*
X72390Y-102513D01*
X71954Y-100180D01*
Y-97846D01*
X72390Y-95513D01*
X73264Y-93471D01*
X74574Y-91722D01*
X76102Y-90555D01*
X77849Y-90263D01*
X79595Y-90555D01*
X81124Y-91722D01*
X82434Y-93471D01*
X83308Y-95513D01*
X83744Y-97846D01*
Y-100180D01*
X83308Y-102513D01*
X82434Y-104555D01*
X81124Y-106305D01*
X79595Y-107471D01*
X77849Y-107763D01*
G01X128690Y-90263D02*
X134149Y-107763D01*
X139608Y-90263D01*
G01X156016Y-107763D02*
X147282D01*
Y-90263D01*
X156016D01*
G01X152522Y-98721D02*
X147282D01*
G01X164782Y-107763D02*
Y-90263D01*
X170241D01*
X171987Y-91138D01*
X173079Y-92305D01*
X173516Y-94638D01*
X173079Y-96972D01*
X171769Y-98430D01*
X170241Y-99305D01*
X164782D01*
G01X170241D02*
X173516Y-107763D01*
G01X186649Y-108346D02*
X186212Y-108055D01*
Y-107471D01*
X186649Y-107180D01*
X187086Y-107471D01*
Y-108055D01*
X186649Y-108346D01*
G01X151649Y-152763D02*
Y-135263D01*
X149029Y-138763D01*
G01Y-152763D02*
X154269D01*
G01X163472D02*
Y-135263D01*
X169149Y-149846D01*
X174826Y-135263D01*
Y-152763D01*
G01X334853Y-143430D02*
X333979Y-142555D01*
X333324Y-141097D01*
X332887Y-139054D01*
X333324Y-137305D01*
X334197Y-136138D01*
X335726Y-135263D01*
X341621D01*
Y-152763D01*
X334416D01*
X332887Y-151597D01*
X332014Y-149846D01*
X331577Y-147805D01*
X332014Y-145763D01*
X333324Y-144013D01*
X334853Y-143430D01*
X341621D01*
G01X324776Y-152763D02*
Y-135263D01*
X319099Y-149846D01*
X313422Y-135263D01*
Y-152763D01*
G01X307058D02*
X301599Y-135263D01*
X296140Y-152763D01*
G01X298106Y-146638D02*
X305093D01*
G01X288684Y-150430D02*
X286937Y-151888D01*
X284972Y-152763D01*
X283226D01*
X281479Y-151888D01*
X280169Y-150430D01*
X279514Y-148388D01*
X279951Y-146347D01*
X281042Y-144596D01*
X283007Y-143430D01*
X285627Y-142846D01*
X287156Y-141680D01*
X287811Y-139638D01*
X287374Y-137596D01*
X286282Y-136138D01*
X284754Y-135263D01*
X283226D01*
X281697Y-135846D01*
X280387Y-137305D01*
G01X271402Y-152763D02*
Y-135263D01*
G01X263106D02*
X271402Y-146055D01*
G01X261796Y-152763D02*
X267691Y-141097D01*
G01X253482Y-90263D02*
Y-107763D01*
X262216D01*
G01X279279D02*
Y-96097D01*
G01Y-98138D02*
X278406Y-96972D01*
X277095Y-96388D01*
X275567Y-96097D01*
X274039Y-96680D01*
X272729Y-97846D01*
X271855Y-99596D01*
X271419Y-101930D01*
X271855Y-104263D01*
X272729Y-106013D01*
X274039Y-107180D01*
X275567Y-107763D01*
X277095Y-107471D01*
X278406Y-106597D01*
X279279Y-105430D01*
G01X288264Y-113013D02*
X289574Y-113596D01*
X291321Y-113013D01*
X292412Y-111847D01*
X293286Y-110388D01*
X294595Y-105722D01*
X297434Y-96097D01*
G01X290447D02*
X294595Y-105722D01*
G01X307074Y-99888D02*
X314061D01*
X313406Y-97846D01*
X312314Y-96680D01*
X310786Y-96097D01*
X309257Y-96388D01*
X307947Y-97263D01*
X307074Y-99305D01*
X306637Y-101055D01*
Y-102805D01*
X307074Y-104555D01*
X308166Y-106305D01*
X309476Y-107471D01*
X311004Y-107763D01*
X312532Y-107180D01*
X314061Y-105430D01*
G01X324792Y-107763D02*
Y-96097D01*
G01Y-98430D02*
X325884Y-97263D01*
X326976Y-96388D01*
X328504Y-96097D01*
X329595Y-96388D01*
X330906Y-97263D01*
G01X342074Y-105722D02*
X343166Y-106888D01*
X344694Y-107763D01*
X346004D01*
X347314Y-107180D01*
X348187Y-106305D01*
X348624Y-105139D01*
X348406Y-103388D01*
X347532Y-102513D01*
X343602Y-100763D01*
X342729Y-98721D01*
X343166Y-97263D01*
X344039Y-96388D01*
X345349Y-96097D01*
X346659Y-96388D01*
X347969Y-97263D01*
G01X404346Y-107763D02*
Y-90263D01*
X408712D01*
X410459Y-91138D01*
X411769Y-92305D01*
X412861Y-94054D01*
X413734Y-96097D01*
X413952Y-99013D01*
X413734Y-101930D01*
X412861Y-103972D01*
X411769Y-105722D01*
X410459Y-106888D01*
X408712Y-107763D01*
X404346D01*
G01X423374Y-99888D02*
X430361D01*
X429706Y-97846D01*
X428614Y-96680D01*
X427086Y-96097D01*
X425557Y-96388D01*
X424247Y-97263D01*
X423374Y-99305D01*
X422937Y-101055D01*
Y-102805D01*
X423374Y-104555D01*
X424466Y-106305D01*
X425776Y-107471D01*
X427304Y-107763D01*
X428832Y-107180D01*
X430361Y-105430D01*
G01X440874Y-105722D02*
X441966Y-106888D01*
X443494Y-107763D01*
X444804D01*
X446114Y-107180D01*
X446987Y-106305D01*
X447424Y-105139D01*
X447206Y-103388D01*
X446332Y-102513D01*
X442402Y-100763D01*
X441529Y-98721D01*
X441966Y-97263D01*
X442839Y-96388D01*
X444149Y-96097D01*
X445459Y-96388D01*
X446769Y-97263D01*
G01X461649Y-96097D02*
Y-107763D01*
G01Y-91430D02*
X461212Y-91138D01*
Y-90555D01*
X461649Y-90263D01*
X462086Y-90555D01*
Y-91138D01*
X461649Y-91430D01*
G01X476092Y-112138D02*
X477621Y-113305D01*
X479367Y-113596D01*
X480895Y-113305D01*
X482206Y-111847D01*
X483079Y-109805D01*
Y-96097D01*
G01Y-98430D02*
X482206Y-97263D01*
X480895Y-96388D01*
X479367Y-96097D01*
X477621Y-96680D01*
X476529Y-97846D01*
X475655Y-99888D01*
X475219Y-101930D01*
X475437Y-103680D01*
X476311Y-105722D01*
X477621Y-107180D01*
X479367Y-107763D01*
X480677Y-107471D01*
X482206Y-106305D01*
X483079Y-105139D01*
G01X492937Y-107763D02*
Y-96097D01*
G01Y-99013D02*
X493811Y-97555D01*
X495121Y-96388D01*
X496867Y-96097D01*
X498395Y-96388D01*
X499706Y-97555D01*
X500361Y-99596D01*
Y-107763D01*
G01X510874Y-99888D02*
X517861D01*
X517206Y-97846D01*
X516114Y-96680D01*
X514586Y-96097D01*
X513057Y-96388D01*
X511747Y-97263D01*
X510874Y-99305D01*
X510437Y-101055D01*
Y-102805D01*
X510874Y-104555D01*
X511966Y-106305D01*
X513276Y-107471D01*
X514804Y-107763D01*
X516332Y-107180D01*
X517861Y-105430D01*
G01X528592Y-107763D02*
Y-96097D01*
G01Y-98430D02*
X529684Y-97263D01*
X530776Y-96388D01*
X532304Y-96097D01*
X533395Y-96388D01*
X534706Y-97263D01*
G01X448096Y-152763D02*
Y-135263D01*
X452462D01*
X454209Y-136138D01*
X455519Y-137305D01*
X456611Y-139054D01*
X457484Y-141097D01*
X457702Y-144013D01*
X457484Y-146930D01*
X456611Y-148972D01*
X455519Y-150722D01*
X454209Y-151888D01*
X452462Y-152763D01*
X448096D01*
G01X470399Y-141097D02*
Y-152763D01*
G01Y-136430D02*
X469962Y-136138D01*
Y-135555D01*
X470399Y-135263D01*
X470836Y-135555D01*
Y-136138D01*
X470399Y-136430D01*
G01X487899Y-152763D02*
X486589Y-152471D01*
X485279Y-151305D01*
X484405Y-149263D01*
X483969Y-146930D01*
X484405Y-144596D01*
X485279Y-142555D01*
X486589Y-141388D01*
X487899Y-141097D01*
X489209Y-141388D01*
X490519Y-142555D01*
X491392Y-144596D01*
X491611Y-146930D01*
X491392Y-149263D01*
X490519Y-151305D01*
X489209Y-152471D01*
X487899Y-152763D01*
G01X575349D02*
Y-135263D01*
X572729Y-138763D01*
G01Y-152763D02*
X577969D01*
G01X588701Y-138180D02*
X590011Y-136430D01*
X591539Y-135555D01*
X593286Y-135263D01*
X595469Y-135846D01*
X596997Y-137305D01*
X597434Y-139054D01*
X597216Y-140805D01*
X596342Y-142263D01*
X591976Y-145180D01*
X590011Y-147221D01*
X588701Y-150139D01*
X588264Y-152763D01*
X597434D01*
G01X606419Y-153346D02*
X614279Y-135263D01*
G01X627849D02*
X626102Y-135846D01*
X624792Y-137305D01*
X623919Y-139054D01*
X623264Y-141388D01*
X623046Y-144013D01*
X623264Y-146638D01*
X623919Y-148972D01*
X624792Y-150722D01*
X626102Y-152180D01*
X627849Y-152763D01*
X629595Y-152180D01*
X630906Y-150722D01*
X631779Y-148972D01*
X632434Y-146638D01*
X632652Y-144013D01*
X632434Y-141388D01*
X631779Y-139054D01*
X630906Y-137305D01*
X629595Y-135846D01*
X627849Y-135263D01*
G01X644912Y-152763D02*
X645349Y-148972D01*
X646004Y-145763D01*
X646877Y-142846D01*
X647969Y-139638D01*
X649716Y-135263D01*
X640982D01*
G01X658919Y-153346D02*
X666779Y-135263D01*
G01X676201Y-138180D02*
X677511Y-136430D01*
X679039Y-135555D01*
X680786Y-135263D01*
X682969Y-135846D01*
X684497Y-137305D01*
X684934Y-139054D01*
X684716Y-140805D01*
X683842Y-142263D01*
X679476Y-145180D01*
X677511Y-147221D01*
X676201Y-150139D01*
X675764Y-152763D01*
X684934D01*
G01X697849Y-135263D02*
X696102Y-135846D01*
X694792Y-137305D01*
X693919Y-139054D01*
X693264Y-141388D01*
X693046Y-144013D01*
X693264Y-146638D01*
X693919Y-148972D01*
X694792Y-150722D01*
X696102Y-152180D01*
X697849Y-152763D01*
X699595Y-152180D01*
X700906Y-150722D01*
X701779Y-148972D01*
X702434Y-146638D01*
X702652Y-144013D01*
X702434Y-141388D01*
X701779Y-139054D01*
X700906Y-137305D01*
X699595Y-135846D01*
X697849Y-135263D01*
G01X715349Y-152763D02*
Y-135263D01*
X712729Y-138763D01*
G01Y-152763D02*
X717969D01*
G01X728701Y-138180D02*
X730011Y-136430D01*
X731539Y-135555D01*
X733286Y-135263D01*
X735469Y-135846D01*
X736997Y-137305D01*
X737434Y-139054D01*
X737216Y-140805D01*
X736342Y-142263D01*
X731976Y-145180D01*
X730011Y-147221D01*
X728701Y-150139D01*
X728264Y-152763D01*
X737434D01*
G01X623046Y-107763D02*
Y-90263D01*
X627412D01*
X629159Y-91138D01*
X630469Y-92305D01*
X631561Y-94054D01*
X632434Y-96097D01*
X632652Y-99013D01*
X632434Y-101930D01*
X631561Y-103972D01*
X630469Y-105722D01*
X629159Y-106888D01*
X627412Y-107763D01*
X623046D01*
G01X649279D02*
Y-96097D01*
G01Y-98138D02*
X648406Y-96972D01*
X647095Y-96388D01*
X645567Y-96097D01*
X644039Y-96680D01*
X642729Y-97846D01*
X641855Y-99596D01*
X641419Y-101930D01*
X641855Y-104263D01*
X642729Y-106013D01*
X644039Y-107180D01*
X645567Y-107763D01*
X647095Y-107471D01*
X648406Y-106597D01*
X649279Y-105430D01*
G01X662849Y-90263D02*
Y-107763D01*
G01X659792Y-96097D02*
X665906D01*
G01X677074Y-99888D02*
X684061D01*
X683406Y-97846D01*
X682314Y-96680D01*
X680786Y-96097D01*
X679257Y-96388D01*
X677947Y-97263D01*
X677074Y-99305D01*
X676637Y-101055D01*
Y-102805D01*
X677074Y-104555D01*
X678166Y-106305D01*
X679476Y-107471D01*
X681004Y-107763D01*
X682532Y-107180D01*
X684061Y-105430D01*
G54D15*
X31299Y230866D03*
Y220866D03*
Y210866D03*
Y338563D03*
Y358563D03*
Y348563D03*
Y903917D03*
Y923917D03*
Y913917D03*
Y1054587D03*
Y1044587D03*
Y1064587D03*
Y1619941D03*
Y1609941D03*
Y1629941D03*
Y1757638D03*
Y1747638D03*
Y1737638D03*
G54D16*
X18035Y572076D03*
X30438Y1367562D03*
X78400Y86100D03*
X58749Y101151D03*
X59104Y441094D03*
X76166Y551466D03*
X38000Y589500D03*
X79000Y675500D03*
X56800Y691000D03*
X42000Y655500D03*
X69600Y662700D03*
X60500Y674700D03*
X80479Y683921D03*
X56800Y831000D03*
X57809Y852500D03*
X52000Y867500D03*
X60900Y893000D03*
X54200Y926700D03*
X67000Y907300D03*
X58500Y912500D03*
X37500Y998000D03*
X57500Y1050500D03*
X58500Y1104500D03*
X56927Y1130027D03*
X31000Y1280500D03*
X76500Y1498500D03*
X37000Y1714000D03*
X71000Y1864500D03*
X75000Y1882000D03*
X127000Y129000D03*
X105300Y525200D03*
X131700Y571100D03*
X82900Y620600D03*
X106400Y648300D03*
X132110Y678353D03*
X83900Y659749D03*
X84000Y674000D03*
X100600Y656600D03*
X128600Y669500D03*
X104000Y734000D03*
X115217Y765517D03*
X111100Y788200D03*
X116402Y779402D03*
X105763Y814263D03*
X122900Y1007400D03*
X88000Y1034500D03*
X91500Y1093000D03*
X121000Y1133000D03*
Y1147500D03*
X122692Y1257808D03*
X124000Y1247600D03*
X91000Y1272500D03*
X89600Y1464000D03*
X95859Y1448359D03*
X101600Y1431000D03*
X122500Y1437509D03*
X119500Y1501000D03*
X108500Y1501500D03*
X114500Y1501800D03*
X104500Y1506000D03*
X130000Y1501000D03*
X125000Y1500500D03*
X81900Y1510200D03*
X108500Y1556500D03*
X97500Y1901000D03*
X93000Y1884500D03*
X154000Y355500D03*
X179300Y530000D03*
X184003Y536497D03*
X136500Y597000D03*
X146000Y641400D03*
X166500Y640000D03*
X137500Y682500D03*
X141800Y676300D03*
X152000Y695688D03*
X173500Y740500D03*
X171000Y1407500D03*
X156000Y1447500D03*
X134000Y1519500D03*
X147500Y1505000D03*
X135000Y1500500D03*
X138500Y1504500D03*
X143518Y1540000D03*
X157000Y1528000D03*
X144500Y1877000D03*
X192007Y482593D03*
G54D17*
X47244Y68110D03*
Y501338D03*
Y761181D03*
Y1207323D03*
Y1467165D03*
Y1900393D03*
G54D18*
X80709Y119409D03*
Y329409D03*
X149606Y119409D03*
Y329409D03*
G54D19*
X80709Y139409D03*
Y309409D03*
X149606Y139409D03*
Y309409D03*
M02*
